(kicad_pcb
	(version 20260206)
	(generator "pcbnew")
	(generator_version "10.0")
	(general
		(thickness 1.6)
		(legacy_teardrops no)
	)
	(paper "A4")
	(title_block
		(title "Wiwynn_Tioga_Pass_MB.brd")
		(comment 1 "Tioga Pass / footprints 4240-4247 of 4770")
	)
	(layers
		(0 "F.Cu" signal "TOP")
		(4 "In1.Cu" signal "L2GND")
		(6 "In2.Cu" signal "L3")
		(8 "In3.Cu" signal "L4GND")
		(10 "In4.Cu" signal "L5")
		(12 "In5.Cu" signal "L6GND")
		(14 "In6.Cu" signal "L7VCC")
		(16 "In7.Cu" signal "L8VCC")
		(18 "In8.Cu" signal "L9GND")
		(20 "In9.Cu" signal "L10")
		(22 "In10.Cu" signal "L11GND")
		(24 "In11.Cu" signal "L12")
		(26 "In12.Cu" signal "L13GND")
		(2 "B.Cu" signal "BOTTOM")
		(9 "F.Adhes" user "F.Adhesive")
		(11 "B.Adhes" user "B.Adhesive")
		(13 "F.Paste" user "Package Geometry/Pastemask Top")
		(15 "B.Paste" user "Package Geometry/Pastemask Bottom")
		(5 "F.SilkS" user "Ref Des/Silkscreen Top")
		(7 "B.SilkS" user "Ref Des/Silkscreen Bottom")
		(1 "F.Mask" user "Board Geometry/Soldermask Top")
		(3 "B.Mask" user "Board Geometry/Soldermask Bottom")
		(17 "Dwgs.User" user "User.Drawings")
		(19 "Cmts.User" user "User.Comments")
		(21 "Eco1.User" user "User.Eco1")
		(23 "Eco2.User" user "User.Eco2")
		(25 "Edge.Cuts" user "Board Geometry/Outline")
		(27 "Margin" user)
		(31 "F.CrtYd" user "Package Geometry/Place Bound Top")
		(29 "B.CrtYd" user "Package Geometry/Place Bound Bottom")
		(35 "F.Fab" user "Ref Des/Assembly Top")
		(33 "B.Fab" user "Ref Des/Assembly Bottom")
	)
	(footprint ""
		(layer "B.Cu")
		(at 456.787758 -32.062674)
		(property "Reference" "R9E14"
			(at 0 0 0)
			(layer "B.SilkS")
			(hide yes)
			(effects
				(font
					(size 1.27 1.27)
				)
				(justify mirror)
			)
		)
		(property "Value" ""
			(at 0 0 0)
			(layer "B.Fab")
			(effects
				(font
					(size 1.27 1.27)
				)
				(justify mirror)
			)
		)
		(duplicate_pad_numbers_are_jumpers no)
		(fp_poly
			(pts
				(xy 0.2794 -0.1016) (xy -0.2794 -0.1016) (xy -0.2794 0.9906) (xy 0.2794 0.9906)
			)
			(stroke
				(width 0)
				(type default)
			)
			(fill no)
			(layer "B.CrtYd")
		)
		(fp_line
			(start -0.2794 -0.1016)
			(end 0.2794 -0.1016)
			(stroke
				(width 0.1)
				(type default)
			)
			(layer "B.Fab")
		)
		(fp_line
			(start -0.2794 0.9906)
			(end -0.2794 -0.1016)
			(stroke
				(width 0.1)
				(type default)
			)
			(layer "B.Fab")
		)
		(fp_line
			(start 0.2794 -0.1016)
			(end 0.2794 0.9906)
			(stroke
				(width 0.1)
				(type default)
			)
			(layer "B.Fab")
		)
		(fp_line
			(start 0.2794 0.9906)
			(end -0.2794 0.9906)
			(stroke
				(width 0.1)
				(type default)
			)
			(layer "B.Fab")
		)
		(pad "1" smd rect
			(at 0 0 180)
			(size 0.508 0.508)
			(layers "B.Cu" "B.Mask" "B.Paste")
			(net "FM_TPM_PRES_RST_N")
		)
		(pad "2" smd rect
			(at 0 0.889 180)
			(size 0.508 0.508)
			(layers "B.Cu" "B.Mask" "B.Paste")
			(net "FM_BMC_ENABLE_N")
		)
		(zone
			(layer "B.Cu")
			(hatch none 0.5)
			(connect_pads
				(clearance 0)
			)
			(min_thickness 0.25)
			(keepout
				(tracks allowed)
				(vias not_allowed)
				(pads allowed)
				(copperpour not_allowed)
				(footprints allowed)
			)
			(placement
				(enabled no)
				(sheetname "")
			)
			(fill
				(thermal_gap 0.5)
				(thermal_bridge_width 0.5)
				(island_removal_mode 0)
			)
			(polygon
				(pts
					(xy 457.041758 -31.808674) (xy 456.533758 -31.808674) (xy 456.533758 -31.427674) (xy 457.041758 -31.427674)
				)
			)
		)
		(zone
			(layer "B.Cu")
			(hatch none 0.5)
			(connect_pads
				(clearance 0)
			)
			(min_thickness 0.25)
			(keepout
				(tracks not_allowed)
				(vias allowed)
				(pads allowed)
				(copperpour not_allowed)
				(footprints allowed)
			)
			(placement
				(enabled no)
				(sheetname "")
			)
			(fill
				(thermal_gap 0.5)
				(thermal_bridge_width 0.5)
				(island_removal_mode 0)
			)
			(polygon
				(pts
					(xy 457.041758 -31.427674) (xy 456.533758 -31.427674) (xy 456.533758 -31.808674) (xy 457.041758 -31.808674)
				)
			)
		)
	)
	(footprint ""
		(layer "B.Cu")
		(at 351.8662 -87.503 -90)
		(property "Reference" "R3P12"
			(at 0 0 90)
			(layer "B.SilkS")
			(hide yes)
			(effects
				(font
					(size 1.27 1.27)
				)
				(justify mirror)
			)
		)
		(property "Value" ""
			(at 0 0 90)
			(layer "B.Fab")
			(effects
				(font
					(size 1.27 1.27)
				)
				(justify mirror)
			)
		)
		(duplicate_pad_numbers_are_jumpers no)
		(fp_poly
			(pts
				(xy 0.2794 -0.1016) (xy -0.2794 -0.1016) (xy -0.2794 0.9906) (xy 0.2794 0.9906)
			)
			(stroke
				(width 0)
				(type default)
			)
			(fill no)
			(layer "B.CrtYd")
		)
		(fp_line
			(start -0.2794 0.9906)
			(end -0.2794 -0.1016)
			(stroke
				(width 0.1)
				(type default)
			)
			(layer "B.Fab")
		)
		(fp_line
			(start 0.2794 0.9906)
			(end -0.2794 0.9906)
			(stroke
				(width 0.1)
				(type default)
			)
			(layer "B.Fab")
		)
		(fp_line
			(start -0.2794 -0.1016)
			(end 0.2794 -0.1016)
			(stroke
				(width 0.1)
				(type default)
			)
			(layer "B.Fab")
		)
		(fp_line
			(start 0.2794 -0.1016)
			(end 0.2794 0.9906)
			(stroke
				(width 0.1)
				(type default)
			)
			(layer "B.Fab")
		)
		(pad "1" smd rect
			(at 0 0 90)
			(size 0.508 0.508)
			(layers "B.Cu" "B.Mask" "B.Paste")
			(net "VR_FET_SW_P12V_STBY_PVCCIO_CPU0")
		)
		(pad "2" smd rect
			(at 0 0.889 90)
			(size 0.508 0.508)
			(layers "B.Cu" "B.Mask" "B.Paste")
			(net "VR_PVCCIO_CPU0_VINSEN")
		)
		(zone
			(layer "B.Cu")
			(hatch none 0.5)
			(connect_pads
				(clearance 0)
			)
			(min_thickness 0.25)
			(keepout
				(tracks not_allowed)
				(vias allowed)
				(pads allowed)
				(copperpour not_allowed)
				(footprints allowed)
			)
			(placement
				(enabled no)
				(sheetname "")
			)
			(fill
				(thermal_gap 0.5)
				(thermal_bridge_width 0.5)
				(island_removal_mode 0)
			)
			(polygon
				(pts
					(xy 351.2312 -87.249) (xy 351.2312 -87.757) (xy 351.6122 -87.757) (xy 351.6122 -87.249)
				)
			)
		)
		(zone
			(layer "B.Cu")
			(hatch none 0.5)
			(connect_pads
				(clearance 0)
			)
			(min_thickness 0.25)
			(keepout
				(tracks allowed)
				(vias not_allowed)
				(pads allowed)
				(copperpour not_allowed)
				(footprints allowed)
			)
			(placement
				(enabled no)
				(sheetname "")
			)
			(fill
				(thermal_gap 0.5)
				(thermal_bridge_width 0.5)
				(island_removal_mode 0)
			)
			(polygon
				(pts
					(xy 351.6122 -87.249) (xy 351.6122 -87.757) (xy 351.2312 -87.757) (xy 351.2312 -87.249)
				)
			)
		)
	)
	(footprint ""
		(layer "B.Cu")
		(at 483.19436 -28.547314)
		(property "Reference" "C2T22"
			(at 0 0 0)
			(layer "B.SilkS")
			(hide yes)
			(effects
				(font
					(size 1.27 1.27)
				)
				(justify mirror)
			)
		)
		(property "Value" ""
			(at 0 0 0)
			(layer "B.Fab")
			(effects
				(font
					(size 1.27 1.27)
				)
				(justify mirror)
			)
		)
		(duplicate_pad_numbers_are_jumpers no)
		(fp_poly
			(pts
				(xy 0.7239 -0.2159) (xy -0.7239 -0.2159) (xy -0.7239 1.9939) (xy 0.7239 1.9939)
			)
			(stroke
				(width 0)
				(type default)
			)
			(fill no)
			(layer "B.CrtYd")
		)
		(fp_line
			(start -0.7239 -0.2159)
			(end 0.7239 -0.2159)
			(stroke
				(width 0.1)
				(type default)
			)
			(layer "B.Fab")
		)
		(fp_line
			(start -0.7239 1.9939)
			(end -0.7239 -0.2159)
			(stroke
				(width 0.1)
				(type default)
			)
			(layer "B.Fab")
		)
		(fp_line
			(start 0.7239 -0.2159)
			(end 0.7239 1.9939)
			(stroke
				(width 0.1)
				(type default)
			)
			(layer "B.Fab")
		)
		(fp_line
			(start 0.7239 1.9939)
			(end -0.7239 1.9939)
			(stroke
				(width 0.1)
				(type default)
			)
			(layer "B.Fab")
		)
		(pad "1" smd rect
			(at 0 0 180)
			(size 1.27 1.016)
			(layers "B.Cu" "B.Mask" "B.Paste")
			(net "P3V3_STBY_MNG")
		)
		(pad "2" smd rect
			(at 0 1.778 180)
			(size 1.27 1.016)
			(layers "B.Cu" "B.Mask" "B.Paste")
			(net "GND")
		)
		(zone
			(layer "B.Cu")
			(hatch none 0.5)
			(connect_pads
				(clearance 0)
			)
			(min_thickness 0.25)
			(keepout
				(tracks not_allowed)
				(vias allowed)
				(pads allowed)
				(copperpour not_allowed)
				(footprints allowed)
			)
			(placement
				(enabled no)
				(sheetname "")
			)
			(fill
				(thermal_gap 0.5)
				(thermal_bridge_width 0.5)
				(island_removal_mode 0)
			)
			(polygon
				(pts
					(xy 483.82936 -28.039314) (xy 482.55936 -28.039314) (xy 482.55936 -27.277314) (xy 483.82936 -27.277314)
				)
			)
		)
	)
	(footprint ""
		(layer "B.Cu")
		(at 414.5534 -142.0368 -90)
		(property "Reference" "C2L37"
			(at 0 0 90)
			(layer "B.SilkS")
			(hide yes)
			(effects
				(font
					(size 1.27 1.27)
				)
				(justify mirror)
			)
		)
		(property "Value" ""
			(at 0 0 90)
			(layer "B.Fab")
			(effects
				(font
					(size 1.27 1.27)
				)
				(justify mirror)
			)
		)
		(duplicate_pad_numbers_are_jumpers no)
		(fp_poly
			(pts
				(xy -0.3048 -0.1016) (xy -0.3048 0.9906) (xy 0.3048 0.9906) (xy 0.3048 -0.1016)
			)
			(stroke
				(width 0)
				(type default)
			)
			(fill no)
			(layer "B.CrtYd")
		)
		(fp_line
			(start -0.3048 0.9906)
			(end -0.3048 -0.1016)
			(stroke
				(width 0.1)
				(type default)
			)
			(layer "B.Fab")
		)
		(fp_line
			(start 0.3048 0.9906)
			(end -0.3048 0.9906)
			(stroke
				(width 0.1)
				(type default)
			)
			(layer "B.Fab")
		)
		(fp_line
			(start -0.3048 -0.1016)
			(end 0.3048 -0.1016)
			(stroke
				(width 0.1)
				(type default)
			)
			(layer "B.Fab")
		)
		(fp_line
			(start 0.3048 -0.1016)
			(end 0.3048 0.9906)
			(stroke
				(width 0.1)
				(type default)
			)
			(layer "B.Fab")
		)
		(pad "1" smd rect
			(at 0 0 90)
			(size 0.508 0.508)
			(layers "B.Cu" "B.Mask" "B.Paste")
			(net "SATA6G_P4_TX_C_DN")
		)
		(pad "2" smd rect
			(at 0 0.889 90)
			(size 0.508 0.508)
			(layers "B.Cu" "B.Mask" "B.Paste")
			(net "SATA6G_PCH_PCIE_UP_SATA_TXN<4>")
		)
		(zone
			(layer "B.Cu")
			(hatch none 0.5)
			(connect_pads
				(clearance 0)
			)
			(min_thickness 0.25)
			(keepout
				(tracks not_allowed)
				(vias allowed)
				(pads allowed)
				(copperpour not_allowed)
				(footprints allowed)
			)
			(placement
				(enabled no)
				(sheetname "")
			)
			(fill
				(thermal_gap 0.5)
				(thermal_bridge_width 0.5)
				(island_removal_mode 0)
			)
			(polygon
				(pts
					(xy 413.9184 -141.7828) (xy 413.9184 -142.2908) (xy 414.2994 -142.2908) (xy 414.2994 -141.7828)
				)
			)
		)
		(zone
			(layer "B.Cu")
			(hatch none 0.5)
			(connect_pads
				(clearance 0)
			)
			(min_thickness 0.25)
			(keepout
				(tracks allowed)
				(vias not_allowed)
				(pads allowed)
				(copperpour not_allowed)
				(footprints allowed)
			)
			(placement
				(enabled no)
				(sheetname "")
			)
			(fill
				(thermal_gap 0.5)
				(thermal_bridge_width 0.5)
				(island_removal_mode 0)
			)
			(polygon
				(pts
					(xy 414.2994 -141.7828) (xy 414.2994 -142.2908) (xy 413.9184 -142.2908) (xy 413.9184 -141.7828)
				)
			)
		)
	)
	(footprint ""
		(layer "B.Cu")
		(at 362.270294 -44.020486)
		(property "Reference" "R2T66"
			(at 0 0 0)
			(layer "B.SilkS")
			(hide yes)
			(effects
				(font
					(size 1.27 1.27)
				)
				(justify mirror)
			)
		)
		(property "Value" ""
			(at 0 0 0)
			(layer "B.Fab")
			(effects
				(font
					(size 1.27 1.27)
				)
				(justify mirror)
			)
		)
		(duplicate_pad_numbers_are_jumpers no)
		(fp_poly
			(pts
				(xy 0.2794 -0.1016) (xy -0.2794 -0.1016) (xy -0.2794 0.9906) (xy 0.2794 0.9906)
			)
			(stroke
				(width 0)
				(type default)
			)
			(fill no)
			(layer "B.CrtYd")
		)
		(fp_line
			(start -0.2794 -0.1016)
			(end 0.2794 -0.1016)
			(stroke
				(width 0.1)
				(type default)
			)
			(layer "B.Fab")
		)
		(fp_line
			(start -0.2794 0.9906)
			(end -0.2794 -0.1016)
			(stroke
				(width 0.1)
				(type default)
			)
			(layer "B.Fab")
		)
		(fp_line
			(start 0.2794 -0.1016)
			(end 0.2794 0.9906)
			(stroke
				(width 0.1)
				(type default)
			)
			(layer "B.Fab")
		)
		(fp_line
			(start 0.2794 0.9906)
			(end -0.2794 0.9906)
			(stroke
				(width 0.1)
				(type default)
			)
			(layer "B.Fab")
		)
		(pad "1" smd rect
			(at 0 0 180)
			(size 0.508 0.508)
			(layers "B.Cu" "B.Mask" "B.Paste")
			(net "FM_CPU_ERR1_LVT3_R_N")
		)
		(pad "2" smd rect
			(at 0 0.889 180)
			(size 0.508 0.508)
			(layers "B.Cu" "B.Mask" "B.Paste")
			(net "FM_CPU_ERR1_LVT3_K_N")
		)
		(zone
			(layer "B.Cu")
			(hatch none 0.5)
			(connect_pads
				(clearance 0)
			)
			(min_thickness 0.25)
			(keepout
				(tracks allowed)
				(vias not_allowed)
				(pads allowed)
				(copperpour not_allowed)
				(footprints allowed)
			)
			(placement
				(enabled no)
				(sheetname "")
			)
			(fill
				(thermal_gap 0.5)
				(thermal_bridge_width 0.5)
				(island_removal_mode 0)
			)
			(polygon
				(pts
					(xy 362.524294 -43.766486) (xy 362.016294 -43.766486) (xy 362.016294 -43.385486) (xy 362.524294 -43.385486)
				)
			)
		)
		(zone
			(layer "B.Cu")
			(hatch none 0.5)
			(connect_pads
				(clearance 0)
			)
			(min_thickness 0.25)
			(keepout
				(tracks not_allowed)
				(vias allowed)
				(pads allowed)
				(copperpour not_allowed)
				(footprints allowed)
			)
			(placement
				(enabled no)
				(sheetname "")
			)
			(fill
				(thermal_gap 0.5)
				(thermal_bridge_width 0.5)
				(island_removal_mode 0)
			)
			(polygon
				(pts
					(xy 362.524294 -43.385486) (xy 362.016294 -43.385486) (xy 362.016294 -43.766486) (xy 362.524294 -43.766486)
				)
			)
		)
	)
	(footprint ""
		(layer "B.Cu")
		(at 262.206486 -77.82814)
		(property "Reference" "C5P25"
			(at 0 0 0)
			(layer "B.SilkS")
			(hide yes)
			(effects
				(font
					(size 1.27 1.27)
				)
				(justify mirror)
			)
		)
		(property "Value" ""
			(at 0 0 0)
			(layer "B.Fab")
			(effects
				(font
					(size 1.27 1.27)
				)
				(justify mirror)
			)
		)
		(duplicate_pad_numbers_are_jumpers no)
		(fp_poly
			(pts
				(xy 0.7239 -0.2159) (xy -0.7239 -0.2159) (xy -0.7239 1.9939) (xy 0.7239 1.9939)
			)
			(stroke
				(width 0)
				(type default)
			)
			(fill no)
			(layer "B.CrtYd")
		)
		(fp_line
			(start -0.7239 -0.2159)
			(end 0.7239 -0.2159)
			(stroke
				(width 0.1)
				(type default)
			)
			(layer "B.Fab")
		)
		(fp_line
			(start -0.7239 1.9939)
			(end -0.7239 -0.2159)
			(stroke
				(width 0.1)
				(type default)
			)
			(layer "B.Fab")
		)
		(fp_line
			(start 0.7239 -0.2159)
			(end 0.7239 1.9939)
			(stroke
				(width 0.1)
				(type default)
			)
			(layer "B.Fab")
		)
		(fp_line
			(start 0.7239 1.9939)
			(end -0.7239 1.9939)
			(stroke
				(width 0.1)
				(type default)
			)
			(layer "B.Fab")
		)
		(pad "1" smd rect
			(at 0 0 180)
			(size 1.27 1.016)
			(layers "B.Cu" "B.Mask" "B.Paste")
			(net "PVCCIN_CPU0")
		)
		(pad "2" smd rect
			(at 0 1.778 180)
			(size 1.27 1.016)
			(layers "B.Cu" "B.Mask" "B.Paste")
			(net "GND")
		)
		(zone
			(layer "B.Cu")
			(hatch none 0.5)
			(connect_pads
				(clearance 0)
			)
			(min_thickness 0.25)
			(keepout
				(tracks not_allowed)
				(vias allowed)
				(pads allowed)
				(copperpour not_allowed)
				(footprints allowed)
			)
			(placement
				(enabled no)
				(sheetname "")
			)
			(fill
				(thermal_gap 0.5)
				(thermal_bridge_width 0.5)
				(island_removal_mode 0)
			)
			(polygon
				(pts
					(xy 262.841486 -77.32014) (xy 261.571486 -77.32014) (xy 261.571486 -76.55814) (xy 262.841486 -76.55814)
				)
			)
		)
	)
	(footprint ""
		(layer "B.Cu")
		(at 87.158068 -140.208 -90)
		(property "Reference" "C5G112"
			(at -1.14681 0.76708 0)
			(unlocked yes)
			(layer "B.SilkS")
			(effects
				(font
					(size 0.7874 0.5842)
					(thickness 0.1524)
				)
				(justify mirror)
			)
		)
		(property "Value" ""
			(at 0 0 90)
			(layer "B.Fab")
			(effects
				(font
					(size 1.27 1.27)
				)
				(justify mirror)
			)
		)
		(duplicate_pad_numbers_are_jumpers no)
		(fp_rect
			(start 0.4953 1.6002)
			(end -0.4953 -0.2032)
			(stroke
				(width 0)
				(type default)
			)
			(fill no)
			(layer "B.CrtYd")
		)
		(fp_line
			(start -0.4953 1.6002)
			(end 0.4953 1.6002)
			(stroke
				(width 0.1)
				(type default)
			)
			(layer "B.Fab")
		)
		(fp_line
			(start 0.4953 1.6002)
			(end 0.4953 -0.2032)
			(stroke
				(width 0.1)
				(type default)
			)
			(layer "B.Fab")
		)
		(fp_line
			(start -0.4953 -0.2032)
			(end -0.4953 1.6002)
			(stroke
				(width 0.1)
				(type default)
			)
			(layer "B.Fab")
		)
		(fp_line
			(start 0.4953 -0.2032)
			(end -0.4953 -0.2032)
			(stroke
				(width 0.1)
				(type default)
			)
			(layer "B.Fab")
		)
		(pad "1" smd rect
			(at 0 0 90)
			(size 0.762 0.889)
			(layers "B.Cu" "B.Mask" "B.Paste")
			(net "PVDDQ_KLM")
		)
		(pad "2" smd rect
			(at 0 1.397 90)
			(size 0.762 0.889)
			(layers "B.Cu" "B.Mask" "B.Paste")
			(net "GND")
		)
		(zone
			(layer "B.Cu")
			(hatch none 0.5)
			(connect_pads
				(clearance 0)
			)
			(min_thickness 0.25)
			(keepout
				(tracks not_allowed)
				(vias allowed)
				(pads allowed)
				(copperpour not_allowed)
				(footprints allowed)
			)
			(placement
				(enabled no)
				(sheetname "")
			)
			(fill
				(thermal_gap 0.5)
				(thermal_bridge_width 0.5)
				(island_removal_mode 0)
			)
			(polygon
				(pts
					(xy 86.205568 -139.827) (xy 86.713568 -139.827) (xy 86.713568 -140.589) (xy 86.205568 -140.589)
				)
			)
		)
	)
	(footprint ""
		(layer "B.Cu")
		(at 227.584 -91.821 90)
		(property "Reference" "R5N3"
			(at 0 0 90)
			(layer "B.SilkS")
			(hide yes)
			(effects
				(font
					(size 1.27 1.27)
				)
				(justify mirror)
			)
		)
		(property "Value" ""
			(at 0 0 90)
			(layer "B.Fab")
			(effects
				(font
					(size 1.27 1.27)
				)
				(justify mirror)
			)
		)
		(duplicate_pad_numbers_are_jumpers no)
		(fp_poly
			(pts
				(xy 0.2794 -0.1016) (xy -0.2794 -0.1016) (xy -0.2794 0.9906) (xy 0.2794 0.9906)
			)
			(stroke
				(width 0)
				(type default)
			)
			(fill no)
			(layer "B.CrtYd")
		)
		(fp_line
			(start 0.2794 -0.1016)
			(end 0.2794 0.9906)
			(stroke
				(width 0.1)
				(type default)
			)
			(layer "B.Fab")
		)
		(fp_line
			(start -0.2794 -0.1016)
			(end 0.2794 -0.1016)
			(stroke
				(width 0.1)
				(type default)
			)
			(layer "B.Fab")
		)
		(fp_line
			(start 0.2794 0.9906)
			(end -0.2794 0.9906)
			(stroke
				(width 0.1)
				(type default)
			)
			(layer "B.Fab")
		)
		(fp_line
			(start -0.2794 0.9906)
			(end -0.2794 -0.1016)
			(stroke
				(width 0.1)
				(type default)
			)
			(layer "B.Fab")
		)
		(pad "1" smd rect
			(at 0 0 270)
			(size 0.508 0.508)
			(layers "B.Cu" "B.Mask" "B.Paste")
			(net "P3V3_STBY")
		)
		(pad "2" smd rect
			(at 0 0.889 270)
			(size 0.508 0.508)
			(layers "B.Cu" "B.Mask" "B.Paste")
			(net "FM_CPU0_PKGID2")
		)
		(zone
			(layer "B.Cu")
			(hatch none 0.5)
			(connect_pads
				(clearance 0)
			)
			(min_thickness 0.25)
			(keepout
				(tracks allowed)
				(vias not_allowed)
				(pads allowed)
				(copperpour not_allowed)
				(footprints allowed)
			)
			(placement
				(enabled no)
				(sheetname "")
			)
			(fill
				(thermal_gap 0.5)
				(thermal_bridge_width 0.5)
				(island_removal_mode 0)
			)
			(polygon
				(pts
					(xy 227.838 -92.075) (xy 227.838 -91.567) (xy 228.219 -91.567) (xy 228.219 -92.075)
				)
			)
		)
		(zone
			(layer "B.Cu")
			(hatch none 0.5)
			(connect_pads
				(clearance 0)
			)
			(min_thickness 0.25)
			(keepout
				(tracks not_allowed)
				(vias allowed)
				(pads allowed)
				(copperpour not_allowed)
				(footprints allowed)
			)
			(placement
				(enabled no)
				(sheetname "")
			)
			(fill
				(thermal_gap 0.5)
				(thermal_bridge_width 0.5)
				(island_removal_mode 0)
			)
			(polygon
				(pts
					(xy 228.219 -92.075) (xy 228.219 -91.567) (xy 227.838 -91.567) (xy 227.838 -92.075)
				)
			)
		)
	)
)
